G04*
G04 #@! TF.GenerationSoftware,Altium Limited,Altium Designer,23.0.1 (38)*
G04*
G04 Layer_Physical_Order=3*
G04 Layer_Color=16440176*
%FSLAX44Y44*%
%MOMM*%
G71*
G04*
G04 #@! TF.SameCoordinates,9A23C038-B079-480F-8166-AFFB5740F5AE*
G04*
G04*
G04 #@! TF.FilePolarity,Positive*
G04*
G01*
G75*
%ADD46C,0.5500*%
%ADD47C,0.5588*%
G36*
X662899Y313154D02*
X664122Y312648D01*
X665223Y311913D01*
X666159Y310977D01*
X666895Y309878D01*
X667402Y308655D01*
X667661Y307358D01*
X667662Y306697D01*
X667632Y10150D01*
X667632Y10150D01*
X667632Y10150D01*
X667632Y9548D01*
X667397Y8368D01*
X666937Y7257D01*
X666269Y6256D01*
X665419Y5405D01*
X664419Y4736D01*
X663307Y4275D01*
X662128Y4039D01*
X661526Y4038D01*
X10450Y4078D01*
X10450Y4078D01*
X10450Y4078D01*
X9822D01*
X8591Y4323D01*
X7432Y4803D01*
X6388Y5501D01*
X5501Y6388D01*
X4803Y7432D01*
X4323Y8591D01*
X4078Y9822D01*
X4078Y10450D01*
X4078Y10450D01*
X4078Y10450D01*
X4058Y306760D01*
D01*
X4058Y307413D01*
X4313Y308693D01*
X4812Y309900D01*
X5537Y310985D01*
X6460Y311909D01*
X7545Y312635D01*
X8751Y313135D01*
X10031Y313391D01*
X10684Y313392D01*
D01*
X660940Y313412D01*
X661602D01*
X662899Y313154D01*
D02*
G37*
%LPC*%
G36*
X635037Y308538D02*
X631983D01*
X631589Y308460D01*
X631188D01*
X628193Y307864D01*
X627822Y307711D01*
X627428Y307632D01*
X624607Y306464D01*
X624273Y306241D01*
X623902Y306087D01*
X621363Y304391D01*
X621079Y304107D01*
X620746Y303883D01*
X618587Y301724D01*
X618363Y301390D01*
X618079Y301106D01*
X616383Y298568D01*
X616229Y298197D01*
X616006Y297863D01*
X614838Y295042D01*
X614759Y294648D01*
X614606Y294277D01*
X614010Y291282D01*
Y290881D01*
X613932Y290487D01*
Y288960D01*
Y287433D01*
X614010Y287039D01*
Y286638D01*
X614606Y283643D01*
X614759Y283272D01*
X614838Y282878D01*
X616006Y280057D01*
X616229Y279723D01*
X616383Y279352D01*
X618079Y276814D01*
X618363Y276529D01*
X618587Y276196D01*
X620746Y274037D01*
X621079Y273813D01*
X621363Y273529D01*
X623902Y271833D01*
X624273Y271679D01*
X624607Y271456D01*
X627428Y270288D01*
X627822Y270209D01*
X628193Y270056D01*
X631188Y269460D01*
X631589D01*
X631983Y269382D01*
X635037D01*
X635431Y269460D01*
X635832D01*
X638827Y270056D01*
X639198Y270209D01*
X639592Y270288D01*
X642413Y271456D01*
X642747Y271679D01*
X643118Y271833D01*
X645657Y273529D01*
X645941Y273813D01*
X646274Y274037D01*
X648434Y276196D01*
X648657Y276530D01*
X648941Y276814D01*
X650637Y279352D01*
X650791Y279723D01*
X651014Y280057D01*
X652182Y282878D01*
X652261Y283272D01*
X652414Y283643D01*
X653010Y286638D01*
Y287039D01*
X653088Y287433D01*
Y288960D01*
Y290487D01*
X653010Y290881D01*
Y291282D01*
X652414Y294277D01*
X652261Y294648D01*
X652182Y295042D01*
X651014Y297863D01*
X650791Y298197D01*
X650637Y298568D01*
X648941Y301106D01*
X648657Y301391D01*
X648434Y301724D01*
X646274Y303883D01*
X645940Y304107D01*
X645657Y304391D01*
X643118Y306087D01*
X642747Y306241D01*
X642413Y306464D01*
X639592Y307632D01*
X639198Y307711D01*
X638827Y307864D01*
X635832Y308460D01*
X635431D01*
X635037Y308538D01*
D02*
G37*
G36*
X30037D02*
X26983D01*
X26589Y308460D01*
X26188D01*
X23193Y307864D01*
X22822Y307711D01*
X22428Y307632D01*
X19607Y306464D01*
X19273Y306241D01*
X18902Y306087D01*
X16364Y304391D01*
X16079Y304107D01*
X15746Y303883D01*
X13586Y301724D01*
X13363Y301390D01*
X13079Y301106D01*
X11383Y298568D01*
X11229Y298197D01*
X11006Y297863D01*
X9838Y295042D01*
X9759Y294648D01*
X9606Y294277D01*
X9010Y291282D01*
Y290881D01*
X8932Y290487D01*
Y288960D01*
Y287433D01*
X9010Y287039D01*
Y286638D01*
X9606Y283643D01*
X9759Y283272D01*
X9838Y282878D01*
X11006Y280057D01*
X11229Y279723D01*
X11383Y279352D01*
X13079Y276814D01*
X13363Y276529D01*
X13586Y276196D01*
X15746Y274037D01*
X16079Y273813D01*
X16364Y273529D01*
X18902Y271833D01*
X19273Y271679D01*
X19607Y271456D01*
X22428Y270288D01*
X22822Y270209D01*
X23193Y270056D01*
X26188Y269460D01*
X26589D01*
X26983Y269382D01*
X30037D01*
X30431Y269460D01*
X30832D01*
X33827Y270056D01*
X34198Y270209D01*
X34592Y270288D01*
X37413Y271456D01*
X37747Y271679D01*
X38118Y271833D01*
X40656Y273529D01*
X40941Y273813D01*
X41274Y274037D01*
X43433Y276196D01*
X43657Y276530D01*
X43941Y276814D01*
X45637Y279352D01*
X45791Y279723D01*
X46014Y280057D01*
X47182Y282878D01*
X47261Y283272D01*
X47414Y283643D01*
X48010Y286638D01*
Y287039D01*
X48088Y287433D01*
Y288960D01*
Y290487D01*
X48010Y290881D01*
Y291282D01*
X47414Y294277D01*
X47261Y294648D01*
X47182Y295042D01*
X46014Y297863D01*
X45791Y298197D01*
X45637Y298568D01*
X43941Y301106D01*
X43657Y301391D01*
X43433Y301724D01*
X41274Y303883D01*
X40940Y304107D01*
X40656Y304391D01*
X38118Y306087D01*
X37747Y306241D01*
X37413Y306464D01*
X34592Y307632D01*
X34198Y307711D01*
X33827Y307864D01*
X30832Y308460D01*
X30431D01*
X30037Y308538D01*
D02*
G37*
G36*
X523910Y246750D02*
X522020D01*
X520274Y246027D01*
X518938Y244691D01*
X518215Y242945D01*
Y241055D01*
X518938Y239309D01*
X520274Y237973D01*
X522020Y237250D01*
X523910D01*
X525656Y237973D01*
X526992Y239309D01*
X527715Y241055D01*
Y242945D01*
X526992Y244691D01*
X525656Y246027D01*
X523910Y246750D01*
D02*
G37*
G36*
X536945Y237441D02*
X535055D01*
X533309Y236717D01*
X531973Y235381D01*
X531250Y233636D01*
Y231746D01*
X531973Y230000D01*
X533309Y228664D01*
X535055Y227941D01*
X536945D01*
X538691Y228664D01*
X540027Y230000D01*
X540750Y231746D01*
Y233636D01*
X540027Y235381D01*
X538691Y236717D01*
X536945Y237441D01*
D02*
G37*
G36*
X523945Y212789D02*
X522055D01*
X520309Y212066D01*
X518973Y210730D01*
X518250Y208984D01*
Y207094D01*
X518973Y205349D01*
X520309Y204013D01*
X522055Y203289D01*
X523945D01*
X525691Y204013D01*
X527027Y205349D01*
X527750Y207094D01*
Y208984D01*
X527027Y210730D01*
X525691Y212066D01*
X523945Y212789D01*
D02*
G37*
G36*
X536945Y212750D02*
X535055D01*
X533309Y212027D01*
X531973Y210691D01*
X531250Y208945D01*
Y207055D01*
X531973Y205309D01*
X533309Y203973D01*
X535055Y203250D01*
X536945D01*
X538691Y203973D01*
X540027Y205309D01*
X540750Y207055D01*
Y208945D01*
X540027Y210691D01*
X538691Y212027D01*
X536945Y212750D01*
D02*
G37*
G36*
X561945Y127750D02*
X560055D01*
X558309Y127027D01*
X556973Y125691D01*
X556250Y123945D01*
Y122055D01*
X556973Y120309D01*
X558309Y118973D01*
X560055Y118250D01*
X561945D01*
X563691Y118973D01*
X565027Y120309D01*
X565750Y122055D01*
Y123945D01*
X565027Y125691D01*
X563691Y127027D01*
X561945Y127750D01*
D02*
G37*
G36*
Y107750D02*
X560055D01*
X558309Y107027D01*
X556973Y105691D01*
X556250Y103945D01*
Y102055D01*
X556973Y100309D01*
X558309Y98973D01*
X560055Y98250D01*
X561945D01*
X563691Y98973D01*
X565027Y100309D01*
X565750Y102055D01*
Y103945D01*
X565027Y105691D01*
X563691Y107027D01*
X561945Y107750D01*
D02*
G37*
G36*
X635037Y48538D02*
X631983D01*
X631589Y48460D01*
X631188D01*
X628193Y47864D01*
X627822Y47711D01*
X627428Y47632D01*
X624607Y46464D01*
X624273Y46241D01*
X623902Y46087D01*
X621363Y44391D01*
X621079Y44107D01*
X620746Y43884D01*
X618587Y41725D01*
X618363Y41391D01*
X618079Y41107D01*
X616383Y38568D01*
X616229Y38197D01*
X616006Y37863D01*
X614838Y35042D01*
X614759Y34648D01*
X614606Y34277D01*
X614010Y31282D01*
Y30881D01*
X613932Y30487D01*
Y28960D01*
Y27433D01*
X614010Y27039D01*
Y26638D01*
X614606Y23643D01*
X614759Y23272D01*
X614838Y22878D01*
X616006Y20057D01*
X616229Y19723D01*
X616383Y19352D01*
X618079Y16813D01*
X618363Y16529D01*
X618587Y16195D01*
X620746Y14037D01*
X621079Y13813D01*
X621363Y13529D01*
X623902Y11833D01*
X624273Y11679D01*
X624607Y11456D01*
X627428Y10288D01*
X627822Y10209D01*
X628193Y10056D01*
X631188Y9460D01*
X631589D01*
X631983Y9382D01*
X635037D01*
X635431Y9460D01*
X635832D01*
X638827Y10056D01*
X639198Y10209D01*
X639592Y10288D01*
X642413Y11456D01*
X642747Y11679D01*
X643118Y11833D01*
X645657Y13529D01*
X645941Y13813D01*
X646274Y14037D01*
X648434Y16195D01*
X648657Y16530D01*
X648941Y16813D01*
X650637Y19352D01*
X650791Y19723D01*
X651014Y20057D01*
X652182Y22878D01*
X652261Y23272D01*
X652414Y23643D01*
X653010Y26638D01*
Y27039D01*
X653088Y27433D01*
Y28960D01*
Y30487D01*
X653010Y30881D01*
Y31282D01*
X652414Y34277D01*
X652261Y34648D01*
X652182Y35042D01*
X651014Y37863D01*
X650791Y38197D01*
X650637Y38568D01*
X648941Y41107D01*
X648657Y41391D01*
X648434Y41725D01*
X646274Y43884D01*
X645940Y44107D01*
X645657Y44391D01*
X643118Y46087D01*
X642747Y46241D01*
X642413Y46464D01*
X639592Y47632D01*
X639198Y47711D01*
X638827Y47864D01*
X635832Y48460D01*
X635431D01*
X635037Y48538D01*
D02*
G37*
G36*
X30037D02*
X26983D01*
X26589Y48460D01*
X26188D01*
X23193Y47864D01*
X22822Y47711D01*
X22428Y47632D01*
X19607Y46464D01*
X19273Y46241D01*
X18902Y46087D01*
X16364Y44391D01*
X16079Y44107D01*
X15746Y43884D01*
X13586Y41725D01*
X13363Y41391D01*
X13079Y41107D01*
X11383Y38568D01*
X11229Y38197D01*
X11006Y37863D01*
X9838Y35042D01*
X9759Y34648D01*
X9606Y34277D01*
X9010Y31282D01*
Y30881D01*
X8932Y30487D01*
Y28960D01*
Y27433D01*
X9010Y27039D01*
Y26638D01*
X9606Y23643D01*
X9759Y23272D01*
X9838Y22878D01*
X11006Y20057D01*
X11229Y19723D01*
X11383Y19352D01*
X13079Y16813D01*
X13363Y16529D01*
X13586Y16195D01*
X15746Y14037D01*
X16079Y13813D01*
X16364Y13529D01*
X18902Y11833D01*
X19273Y11679D01*
X19607Y11456D01*
X22428Y10288D01*
X22822Y10209D01*
X23193Y10056D01*
X26188Y9460D01*
X26589D01*
X26983Y9382D01*
X30037D01*
X30431Y9460D01*
X30832D01*
X33827Y10056D01*
X34198Y10209D01*
X34592Y10288D01*
X37413Y11456D01*
X37747Y11679D01*
X38118Y11833D01*
X40656Y13529D01*
X40941Y13813D01*
X41274Y14037D01*
X43433Y16195D01*
X43657Y16530D01*
X43941Y16813D01*
X45637Y19352D01*
X45791Y19723D01*
X46014Y20057D01*
X47182Y22878D01*
X47261Y23272D01*
X47414Y23643D01*
X48010Y26638D01*
Y27039D01*
X48088Y27433D01*
Y28960D01*
Y30487D01*
X48010Y30881D01*
Y31282D01*
X47414Y34277D01*
X47261Y34648D01*
X47182Y35042D01*
X46014Y37863D01*
X45791Y38197D01*
X45637Y38568D01*
X43941Y41107D01*
X43657Y41391D01*
X43433Y41725D01*
X41274Y43884D01*
X40940Y44107D01*
X40656Y44391D01*
X38118Y46087D01*
X37747Y46241D01*
X37413Y46464D01*
X34592Y47632D01*
X34198Y47711D01*
X33827Y47864D01*
X30832Y48460D01*
X30431D01*
X30037Y48538D01*
D02*
G37*
%LPD*%
D46*
X241871Y254805D02*
D03*
X231291D02*
D03*
X220711D02*
D03*
X210131D02*
D03*
X199634Y253481D02*
D03*
X190160Y248771D02*
D03*
X182390Y241591D02*
D03*
X174908Y234110D02*
D03*
X167427Y226629D02*
D03*
X159946Y219147D02*
D03*
X152465Y211666D02*
D03*
X144033Y205276D02*
D03*
X133555Y203805D02*
D03*
X122976D02*
D03*
X112410Y204354D02*
D03*
X101844Y203805D02*
D03*
X91264D02*
D03*
X80684D02*
D03*
X70105Y203927D02*
D03*
X62147Y210899D02*
D03*
X51602Y210033D02*
D03*
X44897Y201849D02*
D03*
X46109Y191339D02*
D03*
X54498Y184892D02*
D03*
X64966Y186424D02*
D03*
X73834Y192195D02*
D03*
X84414D02*
D03*
X94994D02*
D03*
X116052D02*
D03*
X126632D02*
D03*
X137212Y192229D02*
D03*
X147587Y194300D02*
D03*
X156682Y199706D02*
D03*
X164283Y207065D02*
D03*
X171765Y214546D02*
D03*
X179246Y222027D02*
D03*
X186727Y229508D02*
D03*
X194208Y236989D02*
D03*
X203283Y242429D02*
D03*
X213835Y243195D02*
D03*
X224415D02*
D03*
X234995D02*
D03*
X255209Y245785D02*
D03*
X252362Y255974D02*
D03*
X560000Y143000D02*
D03*
D47*
X175640Y128600D02*
D03*
X124840Y154000D02*
D03*
X150240Y103200D02*
D03*
X404029Y103411D02*
D03*
X455040Y128600D02*
D03*
X429640D02*
D03*
X404240D02*
D03*
X302640Y230200D02*
D03*
X632840Y255600D02*
D03*
Y230200D02*
D03*
Y204800D02*
D03*
Y154000D02*
D03*
Y52400D02*
D03*
X607440Y281000D02*
D03*
Y255600D02*
D03*
Y230200D02*
D03*
Y179400D02*
D03*
Y52400D02*
D03*
Y27000D02*
D03*
X582040Y281000D02*
D03*
Y255600D02*
D03*
Y154000D02*
D03*
Y52400D02*
D03*
X556640Y281000D02*
D03*
Y255600D02*
D03*
Y204800D02*
D03*
Y179400D02*
D03*
Y154000D02*
D03*
Y52400D02*
D03*
X531240Y281000D02*
D03*
Y255600D02*
D03*
Y52400D02*
D03*
X505840Y281000D02*
D03*
Y204800D02*
D03*
Y179400D02*
D03*
Y154000D02*
D03*
Y128600D02*
D03*
Y52400D02*
D03*
X480440Y281000D02*
D03*
Y255600D02*
D03*
Y204800D02*
D03*
Y179400D02*
D03*
Y154000D02*
D03*
Y128600D02*
D03*
Y103200D02*
D03*
Y52400D02*
D03*
X455040Y281000D02*
D03*
Y255600D02*
D03*
Y179400D02*
D03*
Y154000D02*
D03*
Y52400D02*
D03*
X429640Y281000D02*
D03*
Y255600D02*
D03*
Y230200D02*
D03*
Y154000D02*
D03*
Y103200D02*
D03*
Y77800D02*
D03*
Y52400D02*
D03*
X404240Y281000D02*
D03*
Y255600D02*
D03*
Y230200D02*
D03*
Y204800D02*
D03*
Y77800D02*
D03*
Y52400D02*
D03*
X378840Y281000D02*
D03*
Y179400D02*
D03*
Y52400D02*
D03*
X353440Y281000D02*
D03*
Y255600D02*
D03*
Y179400D02*
D03*
Y154000D02*
D03*
Y52400D02*
D03*
X328040Y281000D02*
D03*
Y179400D02*
D03*
Y154000D02*
D03*
Y128600D02*
D03*
Y52400D02*
D03*
X302640Y281000D02*
D03*
Y179400D02*
D03*
Y154000D02*
D03*
Y128600D02*
D03*
Y52400D02*
D03*
X277240Y281000D02*
D03*
Y179400D02*
D03*
Y154000D02*
D03*
Y128600D02*
D03*
Y77800D02*
D03*
Y52400D02*
D03*
X251840Y281000D02*
D03*
Y179400D02*
D03*
Y154000D02*
D03*
Y128600D02*
D03*
Y52400D02*
D03*
X226440Y281000D02*
D03*
Y230200D02*
D03*
Y204800D02*
D03*
Y179400D02*
D03*
Y154000D02*
D03*
Y128600D02*
D03*
Y103200D02*
D03*
Y27000D02*
D03*
X201040Y281000D02*
D03*
Y230200D02*
D03*
Y204800D02*
D03*
Y179400D02*
D03*
Y154000D02*
D03*
Y128600D02*
D03*
Y103200D02*
D03*
Y52400D02*
D03*
Y27000D02*
D03*
X175640Y281000D02*
D03*
Y255600D02*
D03*
Y204800D02*
D03*
Y179400D02*
D03*
Y154000D02*
D03*
Y77800D02*
D03*
Y52400D02*
D03*
Y27000D02*
D03*
X150240Y281000D02*
D03*
Y255600D02*
D03*
Y230200D02*
D03*
Y179400D02*
D03*
Y154000D02*
D03*
Y77800D02*
D03*
Y52400D02*
D03*
Y27000D02*
D03*
X124840Y281000D02*
D03*
Y255600D02*
D03*
Y230200D02*
D03*
Y77800D02*
D03*
Y52400D02*
D03*
Y27000D02*
D03*
X99440Y281000D02*
D03*
Y255600D02*
D03*
Y154000D02*
D03*
Y77800D02*
D03*
Y52400D02*
D03*
Y27000D02*
D03*
X74040Y281000D02*
D03*
Y255600D02*
D03*
Y230200D02*
D03*
Y179400D02*
D03*
Y154000D02*
D03*
Y128600D02*
D03*
Y103200D02*
D03*
Y77800D02*
D03*
Y52400D02*
D03*
Y27000D02*
D03*
X48640Y255600D02*
D03*
Y154000D02*
D03*
Y128600D02*
D03*
Y103200D02*
D03*
Y77800D02*
D03*
Y52400D02*
D03*
X23240Y255600D02*
D03*
Y154000D02*
D03*
Y128600D02*
D03*
Y103200D02*
D03*
Y77800D02*
D03*
Y52400D02*
D03*
M02*
